# T6G (Grand Teton) — schematic netlist excerpt (pin names and nets, part order shuffled) for the footprints in the layout excerpt that follows; sources: Cadence DE-HDL packaged netlist, KiCad conversion of 04192023_DAF0TMB3IC0_F0TG_MB_C_brd_V02_OCP.brd

PC136_6  Q_CAP  0.1UF 25V 10% X7R  pkg 0402  page 220 : A = PVDDCR_CPU1_P1_VCCS ; B = GND
R953  Q_RES  0 5% CHIP  pkg 0201LF  page 276 : A = RST_RT_CPU0_P0_PERST_N ; B = RST_RT_CPU0_P0_PERST_R_N
R1210  Q_RES  0 5% CHIP  pkg 0201LF  page 186 : A = RST_SMB_RT_ROM_R1_N ; B = FM_SMB_RT_ROM_MUX6_SEL

(kicad_pcb
	(version 20260206)
	(generator "pcbnew")
	(generator_version "10.0")
	(general
		(thickness 1.6)
		(legacy_teardrops no)
	)
	(paper "A4")
	(title_block
		(title "04192023_DAF0TMB3IC0_F0TG_MB_C_brd_V02_OCP.brd")
		(comment 1 "Grand Teton / footprints 1015-1017 of 8354")
	)
	(layers
		(0 "F.Cu" signal "TOP")
		(4 "In1.Cu" signal "GND")
		(6 "In2.Cu" signal "IN1")
		(8 "In3.Cu" signal "GND1")
		(10 "In4.Cu" signal "IN2")
		(12 "In5.Cu" signal "GND2")
		(14 "In6.Cu" signal "IN3")
		(16 "In7.Cu" signal "GND3")
		(18 "In8.Cu" signal "VCC")
		(20 "In9.Cu" signal "VCC1")
		(22 "In10.Cu" signal "GND4")
		(24 "In11.Cu" signal "IN4")
		(26 "In12.Cu" signal "GND5")
		(28 "In13.Cu" signal "IN5")
		(30 "In14.Cu" signal "GND6")
		(32 "In15.Cu" signal "IN6")
		(34 "In16.Cu" signal "GND7")
		(2 "B.Cu" signal "BOTTOM")
		(9 "F.Adhes" user "F.Adhesive")
		(11 "B.Adhes" user "B.Adhesive")
		(13 "F.Paste" user "Package Geometry/Pastemask Top")
		(15 "B.Paste" user "Package Geometry/Pastemask Bottom")
		(5 "F.SilkS" user "Ref Des/Silkscreen Top")
		(7 "B.SilkS" user "Ref Des/Silkscreen Bottom")
		(1 "F.Mask" user "Board Geometry/Soldermask Top")
		(3 "B.Mask" user "Board Geometry/Soldermask Bottom")
		(17 "Dwgs.User" user "User.Drawings")
		(19 "Cmts.User" user "User.Comments")
		(21 "Eco1.User" user "User.Eco1")
		(23 "Eco2.User" user "User.Eco2")
		(25 "Edge.Cuts" user "Board Geometry/Outline")
		(27 "Margin" user)
		(31 "F.CrtYd" user "Package Geometry/Place Bound Top")
		(29 "B.CrtYd" user "Package Geometry/Place Bound Bottom")
		(35 "F.Fab" user "Ref Des/Assembly Top")
		(33 "B.Fab" user "Ref Des/Assembly Bottom")
	)
	(footprint ""
		(layer "F.Cu")
		(at 101.035358 -344.796872 90)
		(property "Reference" "PC136_6"
			(at 0 0 90)
			(layer "F.SilkS")
			(hide yes)
			(effects
				(font
					(size 1.27 1.27)
				)
			)
		)
		(property "Value" ""
			(at 0 0 90)
			(layer "F.Fab")
			(effects
				(font
					(size 1.27 1.27)
				)
			)
		)
		(duplicate_pad_numbers_are_jumpers no)
		(fp_line
			(start 0.7874 -0.4064)
			(end 0.7874 0.4064)
			(stroke
				(width 0.1524)
				(type default)
			)
			(layer "F.SilkS")
		)
		(fp_line
			(start -0.7874 -0.4064)
			(end 0.7874 -0.4064)
			(stroke
				(width 0.1524)
				(type default)
			)
			(layer "F.SilkS")
		)
		(fp_line
			(start 0.7874 0.4064)
			(end -0.7874 0.4064)
			(stroke
				(width 0.1524)
				(type default)
			)
			(layer "F.SilkS")
		)
		(fp_line
			(start -0.7874 0.4064)
			(end -0.7874 -0.4064)
			(stroke
				(width 0.1524)
				(type default)
			)
			(layer "F.SilkS")
		)
		(fp_line
			(start -0.12065 -0.305054)
			(end -0.12065 -0.2794)
			(stroke
				(width 0.1)
				(type default)
			)
			(layer "F.Fab")
		)
		(fp_line
			(start -0.67945 -0.305054)
			(end -0.12065 -0.305054)
			(stroke
				(width 0.1)
				(type default)
			)
			(layer "F.Fab")
		)
		(fp_line
			(start 0.67945 -0.3048)
			(end 0.67945 0.3048)
			(stroke
				(width 0.1)
				(type default)
			)
			(layer "F.Fab")
		)
		(fp_line
			(start 0.12065 -0.3048)
			(end 0.67945 -0.3048)
			(stroke
				(width 0.1)
				(type default)
			)
			(layer "F.Fab")
		)
		(fp_line
			(start 0.12065 -0.2794)
			(end 0.12065 -0.3048)
			(stroke
				(width 0.1)
				(type default)
			)
			(layer "F.Fab")
		)
		(fp_line
			(start -0.12065 -0.2794)
			(end 0.12065 -0.2794)
			(stroke
				(width 0.1)
				(type default)
			)
			(layer "F.Fab")
		)
		(fp_line
			(start 0.120396 0.2794)
			(end -0.12065 0.2794)
			(stroke
				(width 0.1)
				(type default)
			)
			(layer "F.Fab")
		)
		(fp_line
			(start -0.12065 0.2794)
			(end -0.12065 0.3048)
			(stroke
				(width 0.1)
				(type default)
			)
			(layer "F.Fab")
		)
		(fp_line
			(start 0.67945 0.3048)
			(end 0.120396 0.3048)
			(stroke
				(width 0.1)
				(type default)
			)
			(layer "F.Fab")
		)
		(fp_line
			(start 0.120396 0.3048)
			(end 0.120396 0.2794)
			(stroke
				(width 0.1)
				(type default)
			)
			(layer "F.Fab")
		)
		(fp_line
			(start -0.12065 0.3048)
			(end -0.67945 0.3048)
			(stroke
				(width 0.1)
				(type default)
			)
			(layer "F.Fab")
		)
		(fp_line
			(start -0.67945 0.3048)
			(end -0.67945 -0.305054)
			(stroke
				(width 0.1)
				(type default)
			)
			(layer "F.Fab")
		)
		(pad "1" smd circle
			(at -0.40005 0 90)
			(size 0 0)
			(layers "F.Cu" "F.Mask" "F.Paste")
			(net "PVDDCR_CPU1_P1_VCCS")
		)
		(pad "2" smd circle
			(at 0.40005 0 90)
			(size 0 0)
			(layers "F.Cu" "F.Mask" "F.Paste")
			(net "GND")
		)
	)
	(footprint ""
		(layer "F.Cu")
		(at 289.136074 -397.85163 -90)
		(property "Reference" "R1210"
			(at 0 0 270)
			(layer "F.SilkS")
			(hide yes)
			(effects
				(font
					(size 1.27 1.27)
				)
			)
		)
		(property "Value" ""
			(at 0 0 270)
			(layer "F.Fab")
			(effects
				(font
					(size 1.27 1.27)
				)
			)
		)
		(duplicate_pad_numbers_are_jumpers no)
		(fp_line
			(start -0.32512 0.175006)
			(end -0.32512 -0.175006)
			(stroke
				(width 0.1)
				(type default)
			)
			(layer "F.Fab")
		)
		(fp_line
			(start 0.32512 0.175006)
			(end -0.32512 0.175006)
			(stroke
				(width 0.1)
				(type default)
			)
			(layer "F.Fab")
		)
		(fp_line
			(start -0.32512 -0.175006)
			(end 0.32512 -0.175006)
			(stroke
				(width 0.1)
				(type default)
			)
			(layer "F.Fab")
		)
		(fp_line
			(start 0.32512 -0.175006)
			(end 0.32512 0.175006)
			(stroke
				(width 0.1)
				(type default)
			)
			(layer "F.Fab")
		)
		(pad "1" smd rect
			(at -0.2667 0 270)
			(size 0.3048 0.381)
			(layers "F.Cu" "F.Mask" "F.Paste")
			(net "RST_SMB_RT_ROM_R1_N")
		)
		(pad "2" smd rect
			(at 0.2667 0 90)
			(size 0.3048 0.381)
			(layers "F.Cu" "F.Mask" "F.Paste")
			(net "FM_SMB_RT_ROM_MUX6_SEL")
		)
	)
	(footprint ""
		(layer "F.Cu")
		(at 324.168262 -404.0124 -90)
		(property "Reference" "R953"
			(at 0 0 270)
			(layer "F.SilkS")
			(hide yes)
			(effects
				(font
					(size 1.27 1.27)
				)
			)
		)
		(property "Value" ""
			(at 0 0 270)
			(layer "F.Fab")
			(effects
				(font
					(size 1.27 1.27)
				)
			)
		)
		(duplicate_pad_numbers_are_jumpers no)
		(fp_line
			(start -0.32512 0.175006)
			(end -0.32512 -0.175006)
			(stroke
				(width 0.1)
				(type default)
			)
			(layer "F.Fab")
		)
		(fp_line
			(start 0.32512 0.175006)
			(end -0.32512 0.175006)
			(stroke
				(width 0.1)
				(type default)
			)
			(layer "F.Fab")
		)
		(fp_line
			(start -0.32512 -0.175006)
			(end 0.32512 -0.175006)
			(stroke
				(width 0.1)
				(type default)
			)
			(layer "F.Fab")
		)
		(fp_line
			(start 0.32512 -0.175006)
			(end 0.32512 0.175006)
			(stroke
				(width 0.1)
				(type default)
			)
			(layer "F.Fab")
		)
		(pad "1" smd rect
			(at -0.2667 0 270)
			(size 0.3048 0.381)
			(layers "F.Cu" "F.Mask" "F.Paste")
			(net "RST_RT_CPU0_P0_PERST_N")
		)
		(pad "2" smd rect
			(at 0.2667 0 90)
			(size 0.3048 0.381)
			(layers "F.Cu" "F.Mask" "F.Paste")
			(net "RST_RT_CPU0_P0_PERST_R_N")
		)
	)
)
